# T6G (Grand Teton) — schematic netlist excerpt (pin names and nets, part order shuffled) for the footprints in the layout excerpt that follows; sources: Cadence DE-HDL packaged netlist, KiCad conversion of 04192023_DAF0TMB3IC0_F0TG_MB_C_brd_V02_OCP.brd

PR482  Q_RES  1.5 1% EMPTY  pkg 0402LF  page 208 : A = SW_PVDD11_S3_P0_SW1_RC ; B = GND
R117  Q_RES  1K 1% CHIP  pkg 0402LF  page 207 : A = P3V3_AUX ; B = PWRGD_PVDD11_S3_P0_R

(kicad_pcb
	(version 20260206)
	(generator "pcbnew")
	(generator_version "10.0")
	(general
		(thickness 1.6)
		(legacy_teardrops no)
	)
	(paper "A4")
	(title_block
		(title "04192023_DAF0TMB3IC0_F0TG_MB_C_brd_V02_OCP.brd")
		(comment 1 "Grand Teton / footprints 1003-1004 of 8354")
	)
	(layers
		(0 "F.Cu" signal "TOP")
		(4 "In1.Cu" signal "GND")
		(6 "In2.Cu" signal "IN1")
		(8 "In3.Cu" signal "GND1")
		(10 "In4.Cu" signal "IN2")
		(12 "In5.Cu" signal "GND2")
		(14 "In6.Cu" signal "IN3")
		(16 "In7.Cu" signal "GND3")
		(18 "In8.Cu" signal "VCC")
		(20 "In9.Cu" signal "VCC1")
		(22 "In10.Cu" signal "GND4")
		(24 "In11.Cu" signal "IN4")
		(26 "In12.Cu" signal "GND5")
		(28 "In13.Cu" signal "IN5")
		(30 "In14.Cu" signal "GND6")
		(32 "In15.Cu" signal "IN6")
		(34 "In16.Cu" signal "GND7")
		(2 "B.Cu" signal "BOTTOM")
		(9 "F.Adhes" user "F.Adhesive")
		(11 "B.Adhes" user "B.Adhesive")
		(13 "F.Paste" user "Package Geometry/Pastemask Top")
		(15 "B.Paste" user "Package Geometry/Pastemask Bottom")
		(5 "F.SilkS" user "Ref Des/Silkscreen Top")
		(7 "B.SilkS" user "Ref Des/Silkscreen Bottom")
		(1 "F.Mask" user "Board Geometry/Soldermask Top")
		(3 "B.Mask" user "Board Geometry/Soldermask Bottom")
		(17 "Dwgs.User" user "User.Drawings")
		(19 "Cmts.User" user "User.Comments")
		(21 "Eco1.User" user "User.Eco1")
		(23 "Eco2.User" user "User.Eco2")
		(25 "Edge.Cuts" user "Board Geometry/Outline")
		(27 "Margin" user)
		(31 "F.CrtYd" user "Package Geometry/Place Bound Top")
		(29 "B.CrtYd" user "Package Geometry/Place Bound Bottom")
		(35 "F.Fab" user "Ref Des/Assembly Top")
		(33 "B.Fab" user "Ref Des/Assembly Bottom")
	)
	(footprint ""
		(layer "F.Cu")
		(at 414.316418 -365.764064)
		(property "Reference" "R117"
			(at 0 0 0)
			(layer "F.SilkS")
			(hide yes)
			(effects
				(font
					(size 1.27 1.27)
				)
			)
		)
		(property "Value" ""
			(at 0 0 0)
			(layer "F.Fab")
			(effects
				(font
					(size 1.27 1.27)
				)
			)
		)
		(duplicate_pad_numbers_are_jumpers no)
		(fp_line
			(start -0.7874 -0.4064)
			(end 0.7874 -0.4064)
			(stroke
				(width 0.1524)
				(type default)
			)
			(layer "F.SilkS")
		)
		(fp_line
			(start -0.7874 0.4064)
			(end -0.7874 -0.4064)
			(stroke
				(width 0.1524)
				(type default)
			)
			(layer "F.SilkS")
		)
		(fp_line
			(start 0.7874 -0.4064)
			(end 0.7874 0.4064)
			(stroke
				(width 0.1524)
				(type default)
			)
			(layer "F.SilkS")
		)
		(fp_line
			(start 0.7874 0.4064)
			(end -0.7874 0.4064)
			(stroke
				(width 0.1524)
				(type default)
			)
			(layer "F.SilkS")
		)
		(fp_line
			(start -0.67945 -0.305054)
			(end -0.12065 -0.305054)
			(stroke
				(width 0.1)
				(type default)
			)
			(layer "F.Fab")
		)
		(fp_line
			(start -0.67945 0.3048)
			(end -0.67945 -0.305054)
			(stroke
				(width 0.1)
				(type default)
			)
			(layer "F.Fab")
		)
		(fp_line
			(start -0.12065 -0.305054)
			(end -0.12065 -0.2794)
			(stroke
				(width 0.1)
				(type default)
			)
			(layer "F.Fab")
		)
		(fp_line
			(start -0.12065 -0.2794)
			(end 0.12065 -0.2794)
			(stroke
				(width 0.1)
				(type default)
			)
			(layer "F.Fab")
		)
		(fp_line
			(start -0.12065 0.2794)
			(end -0.12065 0.3048)
			(stroke
				(width 0.1)
				(type default)
			)
			(layer "F.Fab")
		)
		(fp_line
			(start -0.12065 0.3048)
			(end -0.67945 0.3048)
			(stroke
				(width 0.1)
				(type default)
			)
			(layer "F.Fab")
		)
		(fp_line
			(start 0.120396 0.2794)
			(end -0.12065 0.2794)
			(stroke
				(width 0.1)
				(type default)
			)
			(layer "F.Fab")
		)
		(fp_line
			(start 0.120396 0.3048)
			(end 0.120396 0.2794)
			(stroke
				(width 0.1)
				(type default)
			)
			(layer "F.Fab")
		)
		(fp_line
			(start 0.12065 -0.3048)
			(end 0.67945 -0.3048)
			(stroke
				(width 0.1)
				(type default)
			)
			(layer "F.Fab")
		)
		(fp_line
			(start 0.12065 -0.2794)
			(end 0.12065 -0.3048)
			(stroke
				(width 0.1)
				(type default)
			)
			(layer "F.Fab")
		)
		(fp_line
			(start 0.67945 -0.3048)
			(end 0.67945 0.3048)
			(stroke
				(width 0.1)
				(type default)
			)
			(layer "F.Fab")
		)
		(fp_line
			(start 0.67945 0.3048)
			(end 0.120396 0.3048)
			(stroke
				(width 0.1)
				(type default)
			)
			(layer "F.Fab")
		)
		(pad "1" smd circle
			(at -0.40005 0)
			(size 0 0)
			(layers "F.Cu" "F.Mask" "F.Paste")
			(net "P3V3_AUX")
		)
		(pad "2" smd circle
			(at 0.40005 0)
			(size 0 0)
			(layers "F.Cu" "F.Mask" "F.Paste")
			(net "PWRGD_PVDD11_S3_P0_R")
		)
	)
	(footprint ""
		(layer "F.Cu")
		(at 419.966902 -349.380556 90)
		(property "Reference" "PR482"
			(at 0 0 90)
			(layer "F.SilkS")
			(hide yes)
			(effects
				(font
					(size 1.27 1.27)
				)
			)
		)
		(property "Value" ""
			(at 0 0 90)
			(layer "F.Fab")
			(effects
				(font
					(size 1.27 1.27)
				)
			)
		)
		(duplicate_pad_numbers_are_jumpers no)
		(fp_line
			(start 0.7874 -0.4064)
			(end 0.7874 0.4064)
			(stroke
				(width 0.1524)
				(type default)
			)
			(layer "F.SilkS")
		)
		(fp_line
			(start -0.7874 -0.4064)
			(end 0.7874 -0.4064)
			(stroke
				(width 0.1524)
				(type default)
			)
			(layer "F.SilkS")
		)
		(fp_line
			(start 0.7874 0.4064)
			(end -0.7874 0.4064)
			(stroke
				(width 0.1524)
				(type default)
			)
			(layer "F.SilkS")
		)
		(fp_line
			(start -0.7874 0.4064)
			(end -0.7874 -0.4064)
			(stroke
				(width 0.1524)
				(type default)
			)
			(layer "F.SilkS")
		)
		(fp_line
			(start -0.12065 -0.305054)
			(end -0.12065 -0.2794)
			(stroke
				(width 0.1)
				(type default)
			)
			(layer "F.Fab")
		)
		(fp_line
			(start -0.67945 -0.305054)
			(end -0.12065 -0.305054)
			(stroke
				(width 0.1)
				(type default)
			)
			(layer "F.Fab")
		)
		(fp_line
			(start 0.67945 -0.3048)
			(end 0.67945 0.3048)
			(stroke
				(width 0.1)
				(type default)
			)
			(layer "F.Fab")
		)
		(fp_line
			(start 0.12065 -0.3048)
			(end 0.67945 -0.3048)
			(stroke
				(width 0.1)
				(type default)
			)
			(layer "F.Fab")
		)
		(fp_line
			(start 0.12065 -0.2794)
			(end 0.12065 -0.3048)
			(stroke
				(width 0.1)
				(type default)
			)
			(layer "F.Fab")
		)
		(fp_line
			(start -0.12065 -0.2794)
			(end 0.12065 -0.2794)
			(stroke
				(width 0.1)
				(type default)
			)
			(layer "F.Fab")
		)
		(fp_line
			(start 0.120396 0.2794)
			(end -0.12065 0.2794)
			(stroke
				(width 0.1)
				(type default)
			)
			(layer "F.Fab")
		)
		(fp_line
			(start -0.12065 0.2794)
			(end -0.12065 0.3048)
			(stroke
				(width 0.1)
				(type default)
			)
			(layer "F.Fab")
		)
		(fp_line
			(start 0.67945 0.3048)
			(end 0.120396 0.3048)
			(stroke
				(width 0.1)
				(type default)
			)
			(layer "F.Fab")
		)
		(fp_line
			(start 0.120396 0.3048)
			(end 0.120396 0.2794)
			(stroke
				(width 0.1)
				(type default)
			)
			(layer "F.Fab")
		)
		(fp_line
			(start -0.12065 0.3048)
			(end -0.67945 0.3048)
			(stroke
				(width 0.1)
				(type default)
			)
			(layer "F.Fab")
		)
		(fp_line
			(start -0.67945 0.3048)
			(end -0.67945 -0.305054)
			(stroke
				(width 0.1)
				(type default)
			)
			(layer "F.Fab")
		)
		(pad "1" smd circle
			(at -0.40005 0 90)
			(size 0 0)
			(layers "F.Cu" "F.Mask" "F.Paste")
			(net "SW_PVDD11_S3_P0_SW1_RC")
		)
		(pad "2" smd circle
			(at 0.40005 0 90)
			(size 0 0)
			(layers "F.Cu" "F.Mask" "F.Paste")
			(net "GND")
		)
	)
)
